# S9S_MB_2U (Grand Teton) — schematic netlist excerpt (pin names and nets, part order shuffled) for the footprints in the layout excerpt that follows; sources: Cadence DE-HDL packaged netlist, KiCad conversion of 03242023_DA0F0TMBIJ0_F0T_Motherboard_J_brd_V01_OCP.brd

C2256  Q_CAP  8.2PF 50V 0.1P NP0  pkg C0402  page 212 : A = CLK_GEN2_XTAL_OUT ; B = GND
H120  HOLE  EMPTY  pkg TH  page 311 : \1\ = NC
R626  Q_RES  10K 1% CHIP  pkg 0402LF  page 127 : A = PD_PIROM_CPU1_ADDR2 ; B = GND

(kicad_pcb
	(version 20260206)
	(generator "pcbnew")
	(generator_version "10.0")
	(general
		(thickness 1.6)
		(legacy_teardrops no)
	)
	(paper "A4")
	(title_block
		(title "03242023_DA0F0TMBIJ0_F0T_Motherboard_J_brd_V01_OCP.brd")
		(comment 1 "Grand Teton / footprints 1748-1750 of 6105")
	)
	(layers
		(0 "F.Cu" signal "TOP")
		(4 "In1.Cu" signal "GND")
		(6 "In2.Cu" signal "IN1")
		(8 "In3.Cu" signal "GND1")
		(10 "In4.Cu" signal "IN2")
		(12 "In5.Cu" signal "GND2")
		(14 "In6.Cu" signal "IN3")
		(16 "In7.Cu" signal "GND3")
		(18 "In8.Cu" signal "VCC")
		(20 "In9.Cu" signal "VCC1")
		(22 "In10.Cu" signal "GND4")
		(24 "In11.Cu" signal "IN4")
		(26 "In12.Cu" signal "GND5")
		(28 "In13.Cu" signal "IN5")
		(30 "In14.Cu" signal "GND6")
		(32 "In15.Cu" signal "IN6")
		(34 "In16.Cu" signal "GND7")
		(2 "B.Cu" signal "BOTTOM")
		(9 "F.Adhes" user "F.Adhesive")
		(11 "B.Adhes" user "B.Adhesive")
		(13 "F.Paste" user "Package Geometry/Pastemask Top")
		(15 "B.Paste" user "Package Geometry/Pastemask Bottom")
		(5 "F.SilkS" user "Ref Des/Silkscreen Top")
		(7 "B.SilkS" user "Ref Des/Silkscreen Bottom")
		(1 "F.Mask" user "Board Geometry/Soldermask Top")
		(3 "B.Mask" user "Board Geometry/Soldermask Bottom")
		(17 "Dwgs.User" user "User.Drawings")
		(19 "Cmts.User" user "User.Comments")
		(21 "Eco1.User" user "User.Eco1")
		(23 "Eco2.User" user "User.Eco2")
		(25 "Edge.Cuts" user "Board Geometry/Outline")
		(27 "Margin" user)
		(31 "F.CrtYd" user "Package Geometry/Place Bound Top")
		(29 "B.CrtYd" user "Package Geometry/Place Bound Bottom")
		(35 "F.Fab" user "Ref Des/Assembly Top")
		(33 "B.Fab" user "Ref Des/Assembly Bottom")
	)
	(footprint ""
		(layer "F.Cu")
		(at 193.93408 -352.694748)
		(property "Reference" "R626"
			(at 0 0 0)
			(layer "F.SilkS")
			(hide yes)
			(effects
				(font
					(size 1.27 1.27)
				)
			)
		)
		(property "Value" ""
			(at 0 0 0)
			(layer "F.Fab")
			(effects
				(font
					(size 1.27 1.27)
				)
			)
		)
		(duplicate_pad_numbers_are_jumpers no)
		(fp_line
			(start -0.7874 -0.4064)
			(end 0.7874 -0.4064)
			(stroke
				(width 0.1524)
				(type default)
			)
			(layer "F.SilkS")
		)
		(fp_line
			(start -0.7874 0.4064)
			(end -0.7874 -0.4064)
			(stroke
				(width 0.1524)
				(type default)
			)
			(layer "F.SilkS")
		)
		(fp_line
			(start 0.7874 -0.4064)
			(end 0.7874 0.4064)
			(stroke
				(width 0.1524)
				(type default)
			)
			(layer "F.SilkS")
		)
		(fp_line
			(start 0.7874 0.4064)
			(end -0.7874 0.4064)
			(stroke
				(width 0.1524)
				(type default)
			)
			(layer "F.SilkS")
		)
		(fp_line
			(start -0.67945 -0.305054)
			(end -0.12065 -0.305054)
			(stroke
				(width 0.1)
				(type default)
			)
			(layer "F.Fab")
		)
		(fp_line
			(start -0.67945 0.3048)
			(end -0.67945 -0.305054)
			(stroke
				(width 0.1)
				(type default)
			)
			(layer "F.Fab")
		)
		(fp_line
			(start -0.12065 -0.305054)
			(end -0.12065 -0.2794)
			(stroke
				(width 0.1)
				(type default)
			)
			(layer "F.Fab")
		)
		(fp_line
			(start -0.12065 -0.2794)
			(end 0.12065 -0.2794)
			(stroke
				(width 0.1)
				(type default)
			)
			(layer "F.Fab")
		)
		(fp_line
			(start -0.12065 0.2794)
			(end -0.12065 0.3048)
			(stroke
				(width 0.1)
				(type default)
			)
			(layer "F.Fab")
		)
		(fp_line
			(start -0.12065 0.3048)
			(end -0.67945 0.3048)
			(stroke
				(width 0.1)
				(type default)
			)
			(layer "F.Fab")
		)
		(fp_line
			(start 0.120396 0.2794)
			(end -0.12065 0.2794)
			(stroke
				(width 0.1)
				(type default)
			)
			(layer "F.Fab")
		)
		(fp_line
			(start 0.120396 0.3048)
			(end 0.120396 0.2794)
			(stroke
				(width 0.1)
				(type default)
			)
			(layer "F.Fab")
		)
		(fp_line
			(start 0.12065 -0.3048)
			(end 0.67945 -0.3048)
			(stroke
				(width 0.1)
				(type default)
			)
			(layer "F.Fab")
		)
		(fp_line
			(start 0.12065 -0.2794)
			(end 0.12065 -0.3048)
			(stroke
				(width 0.1)
				(type default)
			)
			(layer "F.Fab")
		)
		(fp_line
			(start 0.67945 -0.3048)
			(end 0.67945 0.3048)
			(stroke
				(width 0.1)
				(type default)
			)
			(layer "F.Fab")
		)
		(fp_line
			(start 0.67945 0.3048)
			(end 0.120396 0.3048)
			(stroke
				(width 0.1)
				(type default)
			)
			(layer "F.Fab")
		)
		(pad "1" smd circle
			(at -0.40005 0)
			(size 0 0)
			(layers "F.Cu" "F.Mask" "F.Paste")
			(net "PD_PIROM_CPU1_ADDR2")
		)
		(pad "2" smd circle
			(at 0.40005 0)
			(size 0 0)
			(layers "F.Cu" "F.Mask" "F.Paste")
			(net "GND")
		)
	)
	(footprint ""
		(layer "F.Cu")
		(at 240.626392 -250.717558 90)
		(property "Reference" "C2256"
			(at 0 0 90)
			(layer "F.SilkS")
			(hide yes)
			(effects
				(font
					(size 1.27 1.27)
				)
			)
		)
		(property "Value" ""
			(at 0 0 90)
			(layer "F.Fab")
			(effects
				(font
					(size 1.27 1.27)
				)
			)
		)
		(duplicate_pad_numbers_are_jumpers no)
		(fp_line
			(start 0.7874 -0.4064)
			(end 0.7874 0.4064)
			(stroke
				(width 0.1524)
				(type default)
			)
			(layer "F.SilkS")
		)
		(fp_line
			(start -0.7874 -0.4064)
			(end 0.7874 -0.4064)
			(stroke
				(width 0.1524)
				(type default)
			)
			(layer "F.SilkS")
		)
		(fp_line
			(start 0.7874 0.4064)
			(end -0.7874 0.4064)
			(stroke
				(width 0.1524)
				(type default)
			)
			(layer "F.SilkS")
		)
		(fp_line
			(start -0.7874 0.4064)
			(end -0.7874 -0.4064)
			(stroke
				(width 0.1524)
				(type default)
			)
			(layer "F.SilkS")
		)
		(fp_line
			(start -0.12065 -0.305054)
			(end -0.12065 -0.2794)
			(stroke
				(width 0.1)
				(type default)
			)
			(layer "F.Fab")
		)
		(fp_line
			(start -0.67945 -0.305054)
			(end -0.12065 -0.305054)
			(stroke
				(width 0.1)
				(type default)
			)
			(layer "F.Fab")
		)
		(fp_line
			(start 0.67945 -0.3048)
			(end 0.67945 0.3048)
			(stroke
				(width 0.1)
				(type default)
			)
			(layer "F.Fab")
		)
		(fp_line
			(start 0.12065 -0.3048)
			(end 0.67945 -0.3048)
			(stroke
				(width 0.1)
				(type default)
			)
			(layer "F.Fab")
		)
		(fp_line
			(start 0.12065 -0.2794)
			(end 0.12065 -0.3048)
			(stroke
				(width 0.1)
				(type default)
			)
			(layer "F.Fab")
		)
		(fp_line
			(start -0.12065 -0.2794)
			(end 0.12065 -0.2794)
			(stroke
				(width 0.1)
				(type default)
			)
			(layer "F.Fab")
		)
		(fp_line
			(start 0.120396 0.2794)
			(end -0.12065 0.2794)
			(stroke
				(width 0.1)
				(type default)
			)
			(layer "F.Fab")
		)
		(fp_line
			(start -0.12065 0.2794)
			(end -0.12065 0.3048)
			(stroke
				(width 0.1)
				(type default)
			)
			(layer "F.Fab")
		)
		(fp_line
			(start 0.67945 0.3048)
			(end 0.120396 0.3048)
			(stroke
				(width 0.1)
				(type default)
			)
			(layer "F.Fab")
		)
		(fp_line
			(start 0.120396 0.3048)
			(end 0.120396 0.2794)
			(stroke
				(width 0.1)
				(type default)
			)
			(layer "F.Fab")
		)
		(fp_line
			(start -0.12065 0.3048)
			(end -0.67945 0.3048)
			(stroke
				(width 0.1)
				(type default)
			)
			(layer "F.Fab")
		)
		(fp_line
			(start -0.67945 0.3048)
			(end -0.67945 -0.305054)
			(stroke
				(width 0.1)
				(type default)
			)
			(layer "F.Fab")
		)
		(pad "1" smd circle
			(at -0.40005 0 90)
			(size 0 0)
			(layers "F.Cu" "F.Mask" "F.Paste")
			(net "CLK_GEN2_XTAL_OUT")
		)
		(pad "2" smd circle
			(at 0.40005 0 90)
			(size 0 0)
			(layers "F.Cu" "F.Mask" "F.Paste")
			(net "GND")
		)
	)
	(footprint ""
		(layer "F.Cu")
		(at 441.885324 -153.78557)
		(property "Reference" "H120"
			(at -0.79248 -7.30377 0)
			(unlocked yes)
			(layer "F.SilkS")
			(effects
				(font
					(size 0.7874 0.5842)
					(thickness 0.1524)
				)
				(justify left)
			)
		)
		(property "Value" ""
			(at 0 0 0)
			(layer "F.Fab")
			(effects
				(font
					(size 1.27 1.27)
				)
			)
		)
		(duplicate_pad_numbers_are_jumpers no)
		(fp_circle
			(center 0 0)
			(end 5.8166 0)
			(stroke
				(width 0.1524)
				(type default)
			)
			(fill no)
			(layer "F.SilkS")
		)
		(fp_circle
			(center 0 0)
			(end 5.8166 0)
			(stroke
				(width 0.1524)
				(type default)
			)
			(fill no)
			(layer "B.SilkS")
		)
		(fp_circle
			(center 0 0)
			(end 5.8166 0)
			(stroke
				(width 0.1)
				(type default)
			)
			(fill no)
			(layer "B.Fab")
		)
		(fp_circle
			(center 0 0)
			(end 5.8166 0)
			(stroke
				(width 0.1)
				(type default)
			)
			(fill no)
			(layer "F.Fab")
		)
		(pad "" np_thru_hole circle
			(at 0 0)
			(size 10.0076 10.0076)
			(drill 10.0076)
			(layers "*.Cu" "*.Mask")
			(clearance 0.381)
			(thermal_gap 0.381)
		)
	)
)
